(kicad_pcb
	(version 20241229)
	(generator "pcbnew")
	(generator_version "9.0")
	(general
		(thickness 1.294)
		(legacy_teardrops no)
	)
	(paper "A3")
	(title_block
		(title "Kintex 410T devboard")
		(date "2024-04-03")
		(rev "1.1.2")
		(comment 9 "footprints 253-256 of 975")
	)
	(layers
		(0 "F.Cu" mixed)
		(4 "In1.Cu" power)
		(6 "In2.Cu" power)
		(8 "In3.Cu" mixed)
		(10 "In4.Cu" power)
		(12 "In5.Cu" mixed)
		(14 "In6.Cu" power)
		(16 "In7.Cu" mixed)
		(18 "In8.Cu" power)
		(2 "B.Cu" mixed)
		(9 "F.Adhes" user "F.Adhesive")
		(11 "B.Adhes" user "B.Adhesive")
		(13 "F.Paste" user)
		(15 "B.Paste" user)
		(5 "F.SilkS" user "F.Silkscreen")
		(7 "B.SilkS" user "B.Silkscreen")
		(1 "F.Mask" user)
		(3 "B.Mask" user)
		(17 "Dwgs.User" user "User.Drawings")
		(19 "Cmts.User" user "User.Comments")
		(21 "Eco1.User" user "User.Eco1")
		(23 "Eco2.User" user "User.Eco2")
		(25 "Edge.Cuts" user)
		(27 "Margin" user)
		(31 "F.CrtYd" user "F.Courtyard")
		(29 "B.CrtYd" user "B.Courtyard")
		(35 "F.Fab" user)
		(33 "B.Fab" user)
	)
	(footprint "antmicro-footprints:C_0402_1005Metric"
		(layer "F.Cu")
		(at 229.25 142.75 180)
		(descr "Capacitor SMD 0402")
		(tags "capacitor SMD 0402")
		(property "Reference" "C366"
			(at -3.65 -0.35 0)
			(layer "F.SilkS")
			(effects
				(font
					(size 0.7 0.7)
					(thickness 0.15)
				)
				(justify right bottom)
			)
		)
		(property "Value" "C_10u_0402"
			(at 0 1.4 0)
			(layer "F.Fab")
			(effects
				(font
					(size 0.7 0.7)
					(thickness 0.15)
				)
				(justify right bottom)
			)
		)
		(property "Description" "SMD Multilayer Ceramic Capacitor, 10 µF, 6.3 V, 0402 [1005 Metric], ± 20%, X5R, CC Series"
			(at 0 0 180)
			(layer "F.Fab")
			(hide yes)
			(effects
				(font
					(size 1.27 1.27)
					(thickness 0.15)
				)
			)
		)
		(property "Author" "Antmicro"
			(at 458.5 285.5 0)
			(layer "F.Fab")
			(hide yes)
			(effects
				(font
					(size 1 1)
					(thickness 0.15)
				)
			)
		)
		(property "Dielectric" ""
			(at 458.5 285.5 0)
			(layer "F.Fab")
			(hide yes)
			(effects
				(font
					(size 1 1)
					(thickness 0.15)
				)
			)
		)
		(property "License" "Apache-2.0"
			(at 458.5 285.5 0)
			(layer "F.Fab")
			(hide yes)
			(effects
				(font
					(size 1 1)
					(thickness 0.15)
				)
			)
		)
		(property "MPN" "CC0402MRX5R5BB106"
			(at 458.5 285.5 0)
			(layer "F.Fab")
			(hide yes)
			(effects
				(font
					(size 1 1)
					(thickness 0.15)
				)
			)
		)
		(property "Manufacturer" "YAGEO"
			(at 458.5 285.5 0)
			(layer "F.Fab")
			(hide yes)
			(effects
				(font
					(size 1 1)
					(thickness 0.15)
				)
			)
		)
		(property "Val" "10u"
			(at 458.5 285.5 0)
			(layer "F.Fab")
			(hide yes)
			(effects
				(font
					(size 1 1)
					(thickness 0.15)
				)
			)
		)
		(property "Voltage" ""
			(at 458.5 285.5 0)
			(layer "F.Fab")
			(hide yes)
			(effects
				(font
					(size 1 1)
					(thickness 0.15)
				)
			)
		)
		(sheetname "Clocks")
		(sheetfile "clocks.kicad_sch")
		(attr smd)
		(fp_rect
			(start -0.925 -0.47)
			(end 0.925 0.47)
			(stroke
				(width 0.05)
				(type default)
			)
			(fill no)
			(layer "F.CrtYd")
		)
		(fp_line
			(start 0.504 0.248)
			(end -0.494 0.248)
			(stroke
				(width 0.15)
				(type solid)
			)
			(layer "F.Fab")
		)
		(fp_line
			(start 0.504 -0.25)
			(end 0.504 0.248)
			(stroke
				(width 0.15)
				(type solid)
			)
			(layer "F.Fab")
		)
		(fp_line
			(start -0.494 0.248)
			(end -0.494 -0.25)
			(stroke
				(width 0.15)
				(type solid)
			)
			(layer "F.Fab")
		)
		(fp_line
			(start -0.494 -0.25)
			(end 0.504 -0.25)
			(stroke
				(width 0.15)
				(type solid)
			)
			(layer "F.Fab")
		)
		(pad "1" smd roundrect
			(at -0.48 0 180)
			(size 0.59 0.64)
			(layers "F.Cu" "F.Mask" "F.Paste")
			(roundrect_rratio 0.25)
			(net 1 "GND")
			(pintype "passive")
		)
		(pad "2" smd roundrect
			(at 0.48 0 180)
			(size 0.59 0.64)
			(layers "F.Cu" "F.Mask" "F.Paste")
			(roundrect_rratio 0.25)
			(net 1231 "Net-(C366-Pad2)")
			(pintype "passive")
		)
	)
	(footprint "antmicro-footprints:C_0402_1005Metric"
		(layer "F.Cu")
		(at 256.345 137.835 180)
		(descr "Capacitor SMD 0402")
		(tags "capacitor SMD 0402")
		(property "Reference" "C236"
			(at -2.2 4.8 0)
			(layer "F.SilkS")
			(effects
				(font
					(size 0.7 0.7)
					(thickness 0.15)
				)
				(justify right bottom)
			)
		)
		(property "Value" "C_10u_0402"
			(at 0 1.4 0)
			(layer "F.Fab")
			(effects
				(font
					(size 0.7 0.7)
					(thickness 0.15)
				)
				(justify right bottom)
			)
		)
		(property "Description" "SMD Multilayer Ceramic Capacitor, 10 µF, 6.3 V, 0402 [1005 Metric], ± 20%, X5R, CC Series"
			(at 0 0 180)
			(layer "F.Fab")
			(hide yes)
			(effects
				(font
					(size 1.27 1.27)
					(thickness 0.15)
				)
			)
		)
		(property "Author" "Antmicro"
			(at 512.69 275.67 0)
			(layer "F.Fab")
			(hide yes)
			(effects
				(font
					(size 1 1)
					(thickness 0.15)
				)
			)
		)
		(property "Dielectric" ""
			(at 512.69 275.67 0)
			(layer "F.Fab")
			(hide yes)
			(effects
				(font
					(size 1 1)
					(thickness 0.15)
				)
			)
		)
		(property "License" "Apache-2.0"
			(at 512.69 275.67 0)
			(layer "F.Fab")
			(hide yes)
			(effects
				(font
					(size 1 1)
					(thickness 0.15)
				)
			)
		)
		(property "MPN" "CC0402MRX5R5BB106"
			(at 512.69 275.67 0)
			(layer "F.Fab")
			(hide yes)
			(effects
				(font
					(size 1 1)
					(thickness 0.15)
				)
			)
		)
		(property "Manufacturer" "YAGEO"
			(at 512.69 275.67 0)
			(layer "F.Fab")
			(hide yes)
			(effects
				(font
					(size 1 1)
					(thickness 0.15)
				)
			)
		)
		(property "Val" "10u"
			(at 512.69 275.67 0)
			(layer "F.Fab")
			(hide yes)
			(effects
				(font
					(size 1 1)
					(thickness 0.15)
				)
			)
		)
		(property "Voltage" ""
			(at 512.69 275.67 0)
			(layer "F.Fab")
			(hide yes)
			(effects
				(font
					(size 1 1)
					(thickness 0.15)
				)
			)
		)
		(sheetname "USB PHY")
		(sheetfile "usb-phy.kicad_sch")
		(attr smd)
		(fp_rect
			(start -0.925 -0.47)
			(end 0.925 0.47)
			(stroke
				(width 0.05)
				(type default)
			)
			(fill no)
			(layer "F.CrtYd")
		)
		(fp_line
			(start 0.504 0.248)
			(end -0.494 0.248)
			(stroke
				(width 0.15)
				(type solid)
			)
			(layer "F.Fab")
		)
		(fp_line
			(start 0.504 -0.25)
			(end 0.504 0.248)
			(stroke
				(width 0.15)
				(type solid)
			)
			(layer "F.Fab")
		)
		(fp_line
			(start -0.494 0.248)
			(end -0.494 -0.25)
			(stroke
				(width 0.15)
				(type solid)
			)
			(layer "F.Fab")
		)
		(fp_line
			(start -0.494 -0.25)
			(end 0.504 -0.25)
			(stroke
				(width 0.15)
				(type solid)
			)
			(layer "F.Fab")
		)
		(pad "1" smd roundrect
			(at -0.48 0 180)
			(size 0.59 0.64)
			(layers "F.Cu" "F.Mask" "F.Paste")
			(roundrect_rratio 0.25)
			(net 1 "GND")
			(pintype "passive")
		)
		(pad "2" smd roundrect
			(at 0.48 0 180)
			(size 0.59 0.64)
			(layers "F.Cu" "F.Mask" "F.Paste")
			(roundrect_rratio 0.25)
			(net 714 "/USB PHY/FTDI_VPHY")
			(pintype "passive")
		)
	)
	(footprint "antmicro-footprints:C_0402_1005Metric"
		(layer "F.Cu")
		(at 220.6 153.6)
		(descr "Capacitor SMD 0402")
		(tags "capacitor SMD 0402")
		(property "Reference" "C267"
			(at -4.75 0.45 0)
			(layer "F.SilkS")
			(effects
				(font
					(size 0.7 0.7)
					(thickness 0.15)
				)
				(justify left bottom)
			)
		)
		(property "Value" "C_100n_0402"
			(at 0 1.169 0)
			(layer "F.Fab")
			(effects
				(font
					(size 0.7 0.7)
					(thickness 0.15)
				)
				(justify left bottom)
			)
		)
		(property "Description" "SMD Multilayer Ceramic Capacitor, 0.1 µF, 50 V, 0402 [1005 Metric], ± 10%, X5R, GRM Series"
			(at 0 0 0)
			(layer "F.Fab")
			(hide yes)
			(effects
				(font
					(size 1.27 1.27)
					(thickness 0.15)
				)
			)
		)
		(property "Author" "Antmicro"
			(at 0 0 0)
			(layer "F.Fab")
			(hide yes)
			(effects
				(font
					(size 1 1)
					(thickness 0.15)
				)
			)
		)
		(property "Dielectric" "X5R"
			(at 0 0 0)
			(layer "F.Fab")
			(hide yes)
			(effects
				(font
					(size 1 1)
					(thickness 0.15)
				)
			)
		)
		(property "License" "Apache-2.0"
			(at 0 0 0)
			(layer "F.Fab")
			(hide yes)
			(effects
				(font
					(size 1 1)
					(thickness 0.15)
				)
			)
		)
		(property "MPN" "GRM155R61H104KE14D"
			(at 0 0 0)
			(layer "F.Fab")
			(hide yes)
			(effects
				(font
					(size 1 1)
					(thickness 0.15)
				)
			)
		)
		(property "Manufacturer" "Murata"
			(at 0 0 0)
			(layer "F.Fab")
			(hide yes)
			(effects
				(font
					(size 1 1)
					(thickness 0.15)
				)
			)
		)
		(property "Val" "100n"
			(at 0 0 0)
			(layer "F.Fab")
			(hide yes)
			(effects
				(font
					(size 1 1)
					(thickness 0.15)
				)
			)
		)
		(property "Voltage" "50V"
			(at 0 0 0)
			(layer "F.Fab")
			(hide yes)
			(effects
				(font
					(size 1 1)
					(thickness 0.15)
				)
			)
		)
		(sheetname "HDMI + Ethernet")
		(sheetfile "hdmi-ethernet.kicad_sch")
		(attr smd)
		(fp_rect
			(start -0.925 -0.47)
			(end 0.925 0.47)
			(stroke
				(width 0.05)
				(type default)
			)
			(fill no)
			(layer "F.CrtYd")
		)
		(fp_line
			(start -0.494 -0.25)
			(end 0.504 -0.25)
			(stroke
				(width 0.15)
				(type solid)
			)
			(layer "F.Fab")
		)
		(fp_line
			(start -0.494 0.248)
			(end -0.494 -0.25)
			(stroke
				(width 0.15)
				(type solid)
			)
			(layer "F.Fab")
		)
		(fp_line
			(start 0.504 -0.25)
			(end 0.504 0.248)
			(stroke
				(width 0.15)
				(type solid)
			)
			(layer "F.Fab")
		)
		(fp_line
			(start 0.504 0.248)
			(end -0.494 0.248)
			(stroke
				(width 0.15)
				(type solid)
			)
			(layer "F.Fab")
		)
		(pad "1" smd roundrect
			(at -0.48 0)
			(size 0.59 0.64)
			(layers "F.Cu" "F.Mask" "F.Paste")
			(roundrect_rratio 0.25)
			(net 1 "GND")
			(pintype "passive")
		)
		(pad "2" smd roundrect
			(at 0.48 0)
			(size 0.59 0.64)
			(layers "F.Cu" "F.Mask" "F.Paste")
			(roundrect_rratio 0.25)
			(net 721 "/HDMI + Ethernet/ETH_3V3")
			(pintype "passive")
		)
	)
	(footprint "antmicro-footprints:QFN-24-1EP_4x4mm_P0.5_EP2.1x2.1mm"
		(layer "F.Cu")
		(at 228.4 163.43 180)
		(property "Reference" "U6"
			(at 3.7 -2.39 180)
			(layer "F.SilkS")
			(effects
				(font
					(size 0.7 0.7)
					(thickness 0.15)
				)
				(justify left bottom)
			)
		)
		(property "Value" "STUSB4500_QFN"
			(at 9.858 4.248 180)
			(layer "F.Fab")
			(effects
				(font
					(size 0.7 0.7)
					(thickness 0.15)
				)
				(justify left bottom)
			)
		)
		(property "Description" "USB Controller USB 2.0 I2C Interface 24-QFN (4x4)"
			(at 0 0 180)
			(layer "F.Fab")
			(hide yes)
			(effects
				(font
					(size 1.27 1.27)
					(thickness 0.15)
				)
			)
		)
		(property "Author" "Antmicro"
			(at 456.8 326.86 0)
			(layer "F.Fab")
			(hide yes)
			(effects
				(font
					(size 1 1)
					(thickness 0.15)
				)
			)
		)
		(property "License" "Apache-2.0"
			(at 456.8 326.86 0)
			(layer "F.Fab")
			(hide yes)
			(effects
				(font
					(size 1 1)
					(thickness 0.15)
				)
			)
		)
		(property "MPN" "STUSB4500QTR"
			(at 456.8 326.86 0)
			(layer "F.Fab")
			(hide yes)
			(effects
				(font
					(size 1 1)
					(thickness 0.15)
				)
			)
		)
		(property "Manufacturer" "STMicroelectronics"
			(at 456.8 326.86 0)
			(layer "F.Fab")
			(hide yes)
			(effects
				(font
					(size 1 1)
					(thickness 0.15)
				)
			)
		)
		(sheetname "Power supply")
		(sheetfile "power-supply.kicad_sch")
		(attr smd)
		(fp_line
			(start 2.108 2.108)
			(end 2.108 1.634)
			(stroke
				(width 0.15)
				(type solid)
			)
			(layer "F.SilkS")
		)
		(fp_line
			(start 2.108 -2.11)
			(end 2.108 -1.635)
			(stroke
				(width 0.15)
				(type solid)
			)
			(layer "F.SilkS")
		)
		(fp_line
			(start 1.634 2.108)
			(end 2.108 2.108)
			(stroke
				(width 0.15)
				(type solid)
			)
			(layer "F.SilkS")
		)
		(fp_line
			(start 1.634 -2.11)
			(end 2.108 -2.11)
			(stroke
				(width 0.15)
				(type solid)
			)
			(layer "F.SilkS")
		)
		(fp_line
			(start -1.635 2.108)
			(end -2.11 2.108)
			(stroke
				(width 0.15)
				(type solid)
			)
			(layer "F.SilkS")
		)
		(fp_line
			(start -1.635 -2.11)
			(end -2.11 -2.11)
			(stroke
				(width 0.15)
				(type solid)
			)
			(layer "F.SilkS")
		)
		(fp_line
			(start -2.11 2.108)
			(end -2.11 1.634)
			(stroke
				(width 0.15)
				(type solid)
			)
			(layer "F.SilkS")
		)
		(fp_line
			(start -2.11 -1.636)
			(end -2.11 -2.11)
			(stroke
				(width 0.15)
				(type solid)
			)
			(layer "F.SilkS")
		)
		(fp_circle
			(center -2.3 -2.3)
			(end -2.25 -2.3)
			(stroke
				(width 0.15)
				(type solid)
			)
			(fill yes)
			(layer "F.SilkS")
		)
		(fp_rect
			(start -2.503 -2.503)
			(end 2.5 2.5)
			(stroke
				(width 0.05)
				(type solid)
			)
			(fill no)
			(layer "F.CrtYd")
		)
		(fp_line
			(start 1.999 1.999)
			(end -2 1.999)
			(stroke
				(width 0.15)
				(type solid)
			)
			(layer "F.Fab")
		)
		(fp_line
			(start 1.999 -2)
			(end 1.999 1.999)
			(stroke
				(width 0.15)
				(type solid)
			)
			(layer "F.Fab")
		)
		(fp_line
			(start -1 -2)
			(end 1.999 -2)
			(stroke
				(width 0.15)
				(type solid)
			)
			(layer "F.Fab")
		)
		(fp_line
			(start -2 1.999)
			(end -2 -1)
			(stroke
				(width 0.15)
				(type solid)
			)
			(layer "F.Fab")
		)
		(fp_line
			(start -2 -1)
			(end -1 -2)
			(stroke
				(width 0.15)
				(type solid)
			)
			(layer "F.Fab")
		)
		(pad "" smd roundrect
			(at -0.5 -0.5 180)
			(size 0.8 0.8)
			(layers "F.Paste")
			(roundrect_rratio 0.238095)
		)
		(pad "" smd roundrect
			(at -0.5 0.5 180)
			(size 0.8 0.8)
			(layers "F.Paste")
			(roundrect_rratio 0.238095)
		)
		(pad "" smd roundrect
			(at 0.5 -0.5 180)
			(size 0.8 0.8)
			(layers "F.Paste")
			(roundrect_rratio 0.238095)
		)
		(pad "" smd roundrect
			(at 0.5 0.5 180)
			(size 0.8 0.8)
			(layers "F.Paste")
			(roundrect_rratio 0.238095)
		)
		(pad "1" smd roundrect
			(at -1.938 -1.25 180)
			(size 0.825 0.25)
			(layers "F.Cu" "F.Mask" "F.Paste")
			(roundrect_rratio 0.25)
			(net 837 "/Power supply/USB_DBG_PD.CC1")
			(pinfunction "CC1DB")
			(pintype "bidirectional")
		)
		(pad "2" smd roundrect
			(at -1.938 -0.75 180)
			(size 0.825 0.25)
			(layers "F.Cu" "F.Mask" "F.Paste")
			(roundrect_rratio 0.25)
			(net 837 "/Power supply/USB_DBG_PD.CC1")
			(pinfunction "CC1")
			(pintype "bidirectional")
		)
		(pad "3" smd roundrect
			(at -1.938 -0.25 180)
			(size 0.825 0.25)
			(layers "F.Cu" "F.Mask" "F.Paste")
			(roundrect_rratio 0.25)
			(net 1140 "unconnected-(U6-NC-Pad3)")
			(pinfunction "NC")
			(pintype "no_connect")
		)
		(pad "4" smd roundrect
			(at -1.938 0.248 180)
			(size 0.825 0.25)
			(layers "F.Cu" "F.Mask" "F.Paste")
			(roundrect_rratio 0.25)
			(net 840 "/Power supply/USB_DBG_PD.CC2")
			(pinfunction "CC2")
			(pintype "bidirectional")
		)
		(pad "5" smd roundrect
			(at -1.938 0.748 180)
			(size 0.825 0.25)
			(layers "F.Cu" "F.Mask" "F.Paste")
			(roundrect_rratio 0.25)
			(net 840 "/Power supply/USB_DBG_PD.CC2")
			(pinfunction "CC2DB")
			(pintype "bidirectional")
		)
		(pad "6" smd roundrect
			(at -1.938 1.249 180)
			(size 0.825 0.25)
			(layers "F.Cu" "F.Mask" "F.Paste")
			(roundrect_rratio 0.25)
			(net 983 "/Power supply/PD_CTRL.RESET")
			(pinfunction "RESET")
			(pintype "input")
		)
		(pad "7" smd roundrect
			(at -1.25 1.937 180)
			(size 0.25 0.825)
			(layers "F.Cu" "F.Mask" "F.Paste")
			(roundrect_rratio 0.25)
			(net 1338 "/I2C.SCL")
			(pinfunction "SCL")
			(pintype "input")
		)
		(pad "8" smd roundrect
			(at -0.75 1.937 180)
			(size 0.25 0.825)
			(layers "F.Cu" "F.Mask" "F.Paste")
			(roundrect_rratio 0.25)
			(net 1336 "/I2C.SDA")
			(pinfunction "SDA")
			(pintype "bidirectional")
		)
		(pad "9" smd roundrect
			(at -0.25 1.937 180)
			(size 0.25 0.825)
			(layers "F.Cu" "F.Mask" "F.Paste")
			(roundrect_rratio 0.25)
			(net 888 "/Power supply/PDBUS_DISCH")
			(pinfunction "DISCH")
			(pintype "bidirectional")
		)
		(pad "10" smd roundrect
			(at 0.248 1.937 180)
			(size 0.25 0.825)
			(layers "F.Cu" "F.Mask" "F.Paste")
			(roundrect_rratio 0.25)
			(net 1 "GND")
			(pinfunction "GND")
			(pintype "power_in")
		)
		(pad "11" smd roundrect
			(at 0.748 1.937 180)
			(size 0.25 0.825)
			(layers "F.Cu" "F.Mask" "F.Paste")
			(roundrect_rratio 0.25)
			(net 1141 "unconnected-(U6-ATTACH-Pad11)")
			(pinfunction "ATTACH")
			(pintype "output+no_connect")
		)
		(pad "12" smd roundrect
			(at 1.249 1.937 180)
			(size 0.25 0.825)
			(layers "F.Cu" "F.Mask" "F.Paste")
			(roundrect_rratio 0.25)
			(net 1 "GND")
			(pinfunction "ADDR0")
			(pintype "input")
		)
		(pad "13" smd roundrect
			(at 1.937 1.249 180)
			(size 0.825 0.25)
			(layers "F.Cu" "F.Mask" "F.Paste")
			(roundrect_rratio 0.25)
			(net 1 "GND")
			(pinfunction "ADDR1")
			(pintype "input")
		)
		(pad "14" smd roundrect
			(at 1.937 0.748 180)
			(size 0.825 0.25)
			(layers "F.Cu" "F.Mask" "F.Paste")
			(roundrect_rratio 0.25)
			(net 771 "/Power supply/PD_PWR_OK3")
			(pinfunction "POWER_OK3")
			(pintype "output")
		)
		(pad "15" smd roundrect
			(at 1.937 0.248 180)
			(size 0.825 0.25)
			(layers "F.Cu" "F.Mask" "F.Paste")
			(roundrect_rratio 0.25)
			(net 1142 "unconnected-(U6-GPIO-Pad15)")
			(pinfunction "GPIO")
			(pintype "output+no_connect")
		)
		(pad "16" smd roundrect
			(at 1.937 -0.25 180)
			(size 0.825 0.25)
			(layers "F.Cu" "F.Mask" "F.Paste")
			(roundrect_rratio 0.25)
			(net 362 "Net-(U6-VBUS_EN_SNK)")
			(pinfunction "VBUS_EN_SNK")
			(pintype "output")
		)
		(pad "17" smd roundrect
			(at 1.937 -0.75 180)
			(size 0.825 0.25)
			(layers "F.Cu" "F.Mask" "F.Paste")
			(roundrect_rratio 0.25)
			(net 1146 "unconnected-(U6-A_B_SIDE-Pad17)")
			(pinfunction "A_B_SIDE")
			(pintype "output+no_connect")
		)
		(pad "18" smd roundrect
			(at 1.937 -1.25 180)
			(size 0.825 0.25)
			(layers "F.Cu" "F.Mask" "F.Paste")
			(roundrect_rratio 0.25)
			(net 880 "/Power supply/VBUS_DIS")
			(pinfunction "VBUS_VS_DISCH")
			(pintype "input")
		)
		(pad "19" smd roundrect
			(at 1.249 -1.938 180)
			(size 0.25 0.825)
			(layers "F.Cu" "F.Mask" "F.Paste")
			(roundrect_rratio 0.25)
			(net 1147 "unconnected-(U6-~{ALERT}-Pad19)")
			(pinfunction "~{ALERT}")
			(pintype "output+no_connect")
		)
		(pad "20" smd roundrect
			(at 0.748 -1.938 180)
			(size 0.25 0.825)
			(layers "F.Cu" "F.Mask" "F.Paste")
			(roundrect_rratio 0.25)
			(net 769 "/Power supply/PD_PWR_OK2")
			(pinfunction "POWER_OK2")
			(pintype "output")
		)
		(pad "21" smd roundrect
			(at 0.248 -1.938 180)
			(size 0.25 0.825)
			(layers "F.Cu" "F.Mask" "F.Paste")
			(roundrect_rratio 0.25)
			(net 143 "/Power supply/VREG_1V2")
			(pinfunction "VREG_1V2")
			(pintype "output")
		)
		(pad "22" smd roundrect
			(at -0.25 -1.938 180)
			(size 0.25 0.825)
			(layers "F.Cu" "F.Mask" "F.Paste")
			(roundrect_rratio 0.25)
			(net 1 "GND")
			(pinfunction "VSYS")
			(pintype "power_in")
		)
		(pad "23" smd roundrect
			(at -0.75 -1.938 180)
			(size 0.25 0.825)
			(layers "F.Cu" "F.Mask" "F.Paste")
			(roundrect_rratio 0.25)
			(net 267 "/Power supply/VREG_2V7")
			(pinfunction "VREG_2V7")
			(pintype "output")
		)
		(pad "24" smd roundrect
			(at -1.25 -1.938 180)
			(size 0.25 0.825)
			(layers "F.Cu" "F.Mask" "F.Paste")
			(roundrect_rratio 0.25)
			(net 5 "/Power supply/PD_VBUS")
			(pinfunction "VDD")
			(pintype "power_in")
		)
		(pad "25" smd rect
			(at 0 0 180)
			(size 2.1 2.1)
			(layers "F.Cu" "F.Mask")
			(net 1 "GND")
			(pinfunction "EP")
			(pintype "power_in")
		)
	)
)
